(kicad_pcb
	(version 20260206)
	(generator "pcbnew")
	(generator_version "10.0")
	(general
		(thickness 1.5755)
		(legacy_teardrops no)
	)
	(paper "A4")
	(title_block
		(title "gnss-rcb-f9t — GPS_MODULE_ZED-F9T.PcbDoc")
		(comment 1 "Time Appliance Project (Time Card) / footprints 8-13 of 44")
	)
	(layers
		(0 "F.Cu" signal "Top Layer")
		(4 "In1.Cu" signal "Int1 (GND)")
		(6 "In2.Cu" signal "Int2 (GND)")
		(2 "B.Cu" signal "Bottom Layer")
		(9 "F.Adhes" user "F.Adhesive")
		(11 "B.Adhes" user "B.Adhesive")
		(13 "F.Paste" user "Top Paste")
		(15 "B.Paste" user "Bottom Paste")
		(5 "F.SilkS" user "Top Overlay")
		(7 "B.SilkS" user "Bottom Overlay")
		(1 "F.Mask" user "Top Solder")
		(3 "B.Mask" user "Bottom Solder")
		(17 "Dwgs.User" user "User.Drawings")
		(19 "Cmts.User" user "User.Comments")
		(21 "Eco1.User" user "User.Eco1")
		(23 "Eco2.User" user "User.Eco2")
		(25 "Edge.Cuts" user)
		(27 "Margin" user)
		(31 "F.CrtYd" user "Top Courtyard")
		(29 "B.CrtYd" user "Bottom Courtyard")
		(35 "F.Fab" user "Top Component Outline")
		(33 "B.Fab" user "Bottom Component Outline")
	)
	(footprint "Vault:FP-0402-L_1_0_0_05-W_0_5-IPC_B"
		(layer "F.Cu")
		(at 133.83201 103.3274 180)
		(property "Reference" "C9"
			(at 1.49491 1.26983 0)
			(unlocked yes)
			(layer "F.SilkS")
			(effects
				(font
					(size 0.8 0.8)
					(thickness 0.15)
				)
			)
		)
		(property "Value" "100nF"
			(at -3.38655 -1.924242 0)
			(unlocked yes)
			(layer "F.SilkS")
			(hide yes)
			(effects
				(font
					(size 1.524 1.524)
					(thickness 0.254)
				)
			)
		)
		(sheetname "Antenna_Supervisor")
		(sheetfile "Antenna_Supervisor.kicad_sch")
		(duplicate_pad_numbers_are_jumpers no)
		(fp_line
			(start 0.73624 0.68623)
			(end -0.73624 0.68623)
			(stroke
				(width 0.2)
				(type solid)
			)
			(layer "F.SilkS")
		)
		(fp_line
			(start 0.73624 -0.68624)
			(end -0.73624 -0.68624)
			(stroke
				(width 0.2)
				(type solid)
			)
			(layer "F.SilkS")
		)
		(fp_line
			(start 0.88624 0.43623)
			(end -0.88624 0.43623)
			(stroke
				(width 0.2)
				(type solid)
			)
			(layer "F.CrtYd")
		)
		(fp_line
			(start 0.88624 -0.43624)
			(end 0.88624 0.43623)
			(stroke
				(width 0.2)
				(type solid)
			)
			(layer "F.CrtYd")
		)
		(fp_line
			(start 0.88624 -0.43624)
			(end -0.88624 -0.43624)
			(stroke
				(width 0.2)
				(type solid)
			)
			(layer "F.CrtYd")
		)
		(fp_line
			(start -0.88624 -0.43624)
			(end -0.88624 0.43623)
			(stroke
				(width 0.2)
				(type solid)
			)
			(layer "F.CrtYd")
		)
		(fp_line
			(start 0.88624 0.43623)
			(end -0.88624 0.43623)
			(stroke
				(width 0.2)
				(type solid)
			)
			(layer "F.Fab")
		)
		(fp_line
			(start 0.88624 -0.43624)
			(end 0.88624 0.43623)
			(stroke
				(width 0.2)
				(type solid)
			)
			(layer "F.Fab")
		)
		(fp_line
			(start 0.88624 -0.43624)
			(end -0.88624 -0.43624)
			(stroke
				(width 0.2)
				(type solid)
			)
			(layer "F.Fab")
		)
		(fp_line
			(start 0.5 0)
			(end -0.5 0)
			(stroke
				(width 0.1)
				(type solid)
			)
			(layer "F.Fab")
		)
		(fp_line
			(start 0 -0.5)
			(end 0 0.49999)
			(stroke
				(width 0.1)
				(type solid)
			)
			(layer "F.Fab")
		)
		(fp_line
			(start -0.88624 -0.43624)
			(end -0.88624 0.43623)
			(stroke
				(width 0.2)
				(type solid)
			)
			(layer "F.Fab")
		)
		(fp_text user "${REFERENCE}"
			(at 0.4572 -1.64587 360)
			(unlocked yes)
			(layer "F.Fab")
			(effects
				(font
					(face "Arial")
					(size 0.63 0.63)
					(thickness 0.1)
				)
				(justify left bottom)
			)
		)
		(pad "1" smd rect
			(at -0.42856 0 180)
			(size 0.61535 0.57247)
			(layers "F.Cu" "F.Mask" "F.Paste")
			(net "VCC")
			(solder_mask_margin 0)
			(solder_paste_margin 0)
		)
		(pad "2" smd rect
			(at 0.42856 0 180)
			(size 0.61535 0.57247)
			(layers "F.Cu" "F.Mask" "F.Paste")
			(net "GND")
			(solder_mask_margin 0)
			(solder_paste_margin 0)
		)
	)
	(footprint "Vault:FP-0402-L_1_0_0_05-W_0_5-IPC_B"
		(layer "F.Cu")
		(at 129.9011 107.2871 180)
		(property "Reference" "C7"
			(at -2.055 -0.02827 0)
			(unlocked yes)
			(layer "F.SilkS")
			(effects
				(font
					(size 0.8 0.8)
					(thickness 0.15)
				)
			)
		)
		(property "Value" "100nF"
			(at -2.95799 -2.352802 0)
			(unlocked yes)
			(layer "F.SilkS")
			(hide yes)
			(effects
				(font
					(size 1.524 1.524)
					(thickness 0.254)
				)
			)
		)
		(sheetname "Antenna_Supervisor")
		(sheetfile "Antenna_Supervisor.kicad_sch")
		(duplicate_pad_numbers_are_jumpers no)
		(fp_line
			(start 0.73623 0.68624)
			(end -0.73624 0.68624)
			(stroke
				(width 0.2)
				(type solid)
			)
			(layer "F.SilkS")
		)
		(fp_line
			(start 0.73623 -0.68624)
			(end -0.73624 -0.68624)
			(stroke
				(width 0.2)
				(type solid)
			)
			(layer "F.SilkS")
		)
		(fp_line
			(start 0.88623 0.43624)
			(end -0.88624 0.43624)
			(stroke
				(width 0.2)
				(type solid)
			)
			(layer "F.CrtYd")
		)
		(fp_line
			(start 0.88623 -0.43624)
			(end 0.88623 0.43624)
			(stroke
				(width 0.2)
				(type solid)
			)
			(layer "F.CrtYd")
		)
		(fp_line
			(start 0.88623 -0.43624)
			(end -0.88624 -0.43624)
			(stroke
				(width 0.2)
				(type solid)
			)
			(layer "F.CrtYd")
		)
		(fp_line
			(start -0.88624 -0.43624)
			(end -0.88624 0.43624)
			(stroke
				(width 0.2)
				(type solid)
			)
			(layer "F.CrtYd")
		)
		(fp_line
			(start 0.88623 0.43624)
			(end -0.88624 0.43624)
			(stroke
				(width 0.2)
				(type solid)
			)
			(layer "F.Fab")
		)
		(fp_line
			(start 0.88623 -0.43624)
			(end 0.88623 0.43624)
			(stroke
				(width 0.2)
				(type solid)
			)
			(layer "F.Fab")
		)
		(fp_line
			(start 0.88623 -0.43624)
			(end -0.88624 -0.43624)
			(stroke
				(width 0.2)
				(type solid)
			)
			(layer "F.Fab")
		)
		(fp_line
			(start 0.5 0)
			(end -0.5 0)
			(stroke
				(width 0.1)
				(type solid)
			)
			(layer "F.Fab")
		)
		(fp_line
			(start 0 -0.5)
			(end 0 0.5)
			(stroke
				(width 0.1)
				(type solid)
			)
			(layer "F.Fab")
		)
		(fp_line
			(start -0.88624 -0.43624)
			(end -0.88624 0.43624)
			(stroke
				(width 0.2)
				(type solid)
			)
			(layer "F.Fab")
		)
		(fp_text user "${REFERENCE}"
			(at -1.2954 -0.37587 360)
			(unlocked yes)
			(layer "F.Fab")
			(effects
				(font
					(face "Arial")
					(size 0.63 0.63)
					(thickness 0.1)
				)
				(justify left bottom)
			)
		)
		(pad "1" smd rect
			(at -0.42856 0 180)
			(size 0.61535 0.57247)
			(layers "F.Cu" "F.Mask" "F.Paste")
			(net "VCC")
			(solder_mask_margin 0)
			(solder_paste_margin 0)
		)
		(pad "2" smd rect
			(at 0.42856 0 180)
			(size 0.61535 0.57247)
			(layers "F.Cu" "F.Mask" "F.Paste")
			(net "GND")
			(solder_mask_margin 0)
			(solder_paste_margin 0)
		)
	)
	(footprint "Vault:FP-RMCF0402-MFG"
		(layer "F.Cu")
		(at 136.0225 103.2739 180)
		(property "Reference" "R13"
			(at -1.013615 1.41953 360)
			(unlocked yes)
			(layer "F.SilkS")
			(effects
				(font
					(size 0.8 0.8)
					(thickness 0.15001)
				)
			)
		)
		(property "Value" "1k"
			(at -2.530602 0.72357 90)
			(unlocked yes)
			(layer "F.SilkS")
			(hide yes)
			(effects
				(font
					(size 1.524 1.524)
					(thickness 0.254)
				)
			)
		)
		(sheetname "Antenna_Supervisor")
		(sheetfile "Antenna_Supervisor.kicad_sch")
		(duplicate_pad_numbers_are_jumpers no)
		(fp_line
			(start 0.55 0.7)
			(end -0.55 0.7)
			(stroke
				(width 0.2)
				(type solid)
			)
			(layer "F.SilkS")
		)
		(fp_line
			(start 0.55 -0.7)
			(end -0.55 -0.7)
			(stroke
				(width 0.2)
				(type solid)
			)
			(layer "F.SilkS")
		)
		(fp_line
			(start 0.85 0.4)
			(end -0.85 0.4)
			(stroke
				(width 0.2)
				(type solid)
			)
			(layer "F.CrtYd")
		)
		(fp_line
			(start 0.85 -0.4)
			(end 0.85 0.4)
			(stroke
				(width 0.2)
				(type solid)
			)
			(layer "F.CrtYd")
		)
		(fp_line
			(start 0.85 -0.4)
			(end -0.85 -0.4)
			(stroke
				(width 0.2)
				(type solid)
			)
			(layer "F.CrtYd")
		)
		(fp_line
			(start -0.85 -0.4)
			(end -0.85 0.4)
			(stroke
				(width 0.2)
				(type solid)
			)
			(layer "F.CrtYd")
		)
		(fp_line
			(start 0.85 0.4)
			(end -0.85 0.4)
			(stroke
				(width 0.2)
				(type solid)
			)
			(layer "F.Fab")
		)
		(fp_line
			(start 0.85 -0.4)
			(end 0.85 0.4)
			(stroke
				(width 0.2)
				(type solid)
			)
			(layer "F.Fab")
		)
		(fp_line
			(start 0.85 -0.4)
			(end -0.85 -0.4)
			(stroke
				(width 0.2)
				(type solid)
			)
			(layer "F.Fab")
		)
		(fp_line
			(start 0.5 0)
			(end -0.5 0)
			(stroke
				(width 0.1)
				(type solid)
			)
			(layer "F.Fab")
		)
		(fp_line
			(start 0 -0.5)
			(end 0 0.5)
			(stroke
				(width 0.1)
				(type solid)
			)
			(layer "F.Fab")
		)
		(fp_line
			(start -0.85 -0.4)
			(end -0.85 0.4)
			(stroke
				(width 0.2)
				(type solid)
			)
			(layer "F.Fab")
		)
		(fp_text user "${REFERENCE}"
			(at -0.00001 0.09556 180)
			(unlocked yes)
			(layer "F.Fab")
			(effects
				(font
					(face "Arial")
					(size 0.63 0.63)
					(thickness 0.1)
				)
				(justify left bottom)
			)
		)
		(pad "1" smd rect
			(at -0.5 0 180)
			(size 0.5 0.6)
			(layers "F.Cu" "F.Mask" "F.Paste")
			(net "ANT_DET")
			(solder_mask_margin 0)
			(solder_paste_margin 0)
		)
		(pad "2" smd rect
			(at 0.5 0 180)
			(size 0.5 0.6)
			(layers "F.Cu" "F.Mask" "F.Paste")
			(net "VCC")
			(solder_mask_margin 0)
			(solder_paste_margin 0)
		)
	)
	(footprint "Vault:FP-RMCF0402-MFG"
		(layer "F.Cu")
		(at 135.9971 108.6333 180)
		(property "Reference" "R14"
			(at -0.429415 -1.57767 360)
			(unlocked yes)
			(layer "F.SilkS")
			(effects
				(font
					(size 0.8 0.8)
					(thickness 0.15001)
				)
			)
		)
		(property "Value" "1k"
			(at -2.530602 0.72357 90)
			(unlocked yes)
			(layer "F.SilkS")
			(hide yes)
			(effects
				(font
					(size 1.524 1.524)
					(thickness 0.254)
				)
			)
		)
		(sheetname "Antenna_Supervisor")
		(sheetfile "Antenna_Supervisor.kicad_sch")
		(duplicate_pad_numbers_are_jumpers no)
		(fp_line
			(start 0.55 0.7)
			(end -0.55 0.7)
			(stroke
				(width 0.2)
				(type solid)
			)
			(layer "F.SilkS")
		)
		(fp_line
			(start 0.55 -0.7)
			(end -0.55 -0.7)
			(stroke
				(width 0.2)
				(type solid)
			)
			(layer "F.SilkS")
		)
		(fp_line
			(start 0.85 0.4)
			(end -0.85 0.4)
			(stroke
				(width 0.2)
				(type solid)
			)
			(layer "F.CrtYd")
		)
		(fp_line
			(start 0.85 -0.4)
			(end 0.85 0.4)
			(stroke
				(width 0.2)
				(type solid)
			)
			(layer "F.CrtYd")
		)
		(fp_line
			(start 0.85 -0.4)
			(end -0.85 -0.4)
			(stroke
				(width 0.2)
				(type solid)
			)
			(layer "F.CrtYd")
		)
		(fp_line
			(start -0.85 -0.4)
			(end -0.85 0.4)
			(stroke
				(width 0.2)
				(type solid)
			)
			(layer "F.CrtYd")
		)
		(fp_line
			(start 0.85 0.4)
			(end -0.85 0.4)
			(stroke
				(width 0.2)
				(type solid)
			)
			(layer "F.Fab")
		)
		(fp_line
			(start 0.85 -0.4)
			(end 0.85 0.4)
			(stroke
				(width 0.2)
				(type solid)
			)
			(layer "F.Fab")
		)
		(fp_line
			(start 0.85 -0.4)
			(end -0.85 -0.4)
			(stroke
				(width 0.2)
				(type solid)
			)
			(layer "F.Fab")
		)
		(fp_line
			(start 0.5 0)
			(end -0.5 0)
			(stroke
				(width 0.1)
				(type solid)
			)
			(layer "F.Fab")
		)
		(fp_line
			(start 0 -0.5)
			(end 0 0.5)
			(stroke
				(width 0.1)
				(type solid)
			)
			(layer "F.Fab")
		)
		(fp_line
			(start -0.85 -0.4)
			(end -0.85 0.4)
			(stroke
				(width 0.2)
				(type solid)
			)
			(layer "F.Fab")
		)
		(fp_text user "${REFERENCE}"
			(at -0.00001 0.10711 180)
			(unlocked yes)
			(layer "F.Fab")
			(effects
				(font
					(face "Arial")
					(size 0.63 0.63)
					(thickness 0.1)
				)
				(justify left bottom)
			)
		)
		(pad "1" smd rect
			(at -0.5 0 180)
			(size 0.5 0.6)
			(layers "F.Cu" "F.Mask" "F.Paste")
			(net "ANT_SHORT_N")
			(solder_mask_margin 0)
			(solder_paste_margin 0)
		)
		(pad "2" smd rect
			(at 0.5 0 180)
			(size 0.5 0.6)
			(layers "F.Cu" "F.Mask" "F.Paste")
			(net "VCC")
			(solder_mask_margin 0)
			(solder_paste_margin 0)
		)
	)
	(footprint "Vault:FP-RMCF0402-IPC_C"
		(layer "F.Cu")
		(at 130.6631 116.25835)
		(property "Reference" "R9"
			(at -1.7296 0.20607 0)
			(unlocked yes)
			(layer "F.SilkS")
			(effects
				(font
					(size 0.8 0.8)
					(thickness 0.15)
				)
			)
		)
		(property "Value" "100k"
			(at 2.06928 2.225802 0)
			(unlocked yes)
			(layer "F.SilkS")
			(hide yes)
			(effects
				(font
					(size 1.524 1.524)
					(thickness 0.254)
				)
			)
		)
		(sheetname "Antenna_Supervisor")
		(sheetfile "Antenna_Supervisor.kicad_sch")
		(duplicate_pad_numbers_are_jumpers no)
		(fp_line
			(start -0.65606 -0.675)
			(end 0.65607 -0.675)
			(stroke
				(width 0.2)
				(type solid)
			)
			(layer "F.SilkS")
		)
		(fp_line
			(start -0.65606 0.675)
			(end 0.65607 0.675)
			(stroke
				(width 0.2)
				(type solid)
			)
			(layer "F.SilkS")
		)
		(fp_line
			(start -0.75606 -0.375)
			(end 0.75607 -0.375)
			(stroke
				(width 0.2)
				(type solid)
			)
			(layer "F.CrtYd")
		)
		(fp_line
			(start -0.75606 0.375)
			(end -0.75606 -0.375)
			(stroke
				(width 0.2)
				(type solid)
			)
			(layer "F.CrtYd")
		)
		(fp_line
			(start -0.75606 0.375)
			(end 0.75607 0.375)
			(stroke
				(width 0.2)
				(type solid)
			)
			(layer "F.CrtYd")
		)
		(fp_line
			(start 0.75607 0.375)
			(end 0.75607 -0.375)
			(stroke
				(width 0.2)
				(type solid)
			)
			(layer "F.CrtYd")
		)
		(fp_line
			(start -0.75606 -0.375)
			(end 0.75607 -0.375)
			(stroke
				(width 0.2)
				(type solid)
			)
			(layer "F.Fab")
		)
		(fp_line
			(start -0.75606 0.375)
			(end -0.75606 -0.375)
			(stroke
				(width 0.2)
				(type solid)
			)
			(layer "F.Fab")
		)
		(fp_line
			(start -0.75606 0.375)
			(end 0.75607 0.375)
			(stroke
				(width 0.2)
				(type solid)
			)
			(layer "F.Fab")
		)
		(fp_line
			(start -0.5 0)
			(end 0.5 0)
			(stroke
				(width 0.1)
				(type solid)
			)
			(layer "F.Fab")
		)
		(fp_line
			(start 0 0.5)
			(end 0 -0.5)
			(stroke
				(width 0.1)
				(type solid)
			)
			(layer "F.Fab")
		)
		(fp_line
			(start 0.75607 0.375)
			(end 0.75607 -0.375)
			(stroke
				(width 0.2)
				(type solid)
			)
			(layer "F.Fab")
		)
		(fp_text user "${REFERENCE}"
			(at -0.00001 0.09648 360)
			(unlocked yes)
			(layer "F.Fab")
			(effects
				(font
					(face "Arial")
					(size 0.63 0.63)
					(thickness 0.1)
				)
				(justify left bottom)
			)
		)
		(pad "1" smd rect
			(at -0.36553 0)
			(size 0.58106 0.47247)
			(layers "F.Cu" "F.Mask" "F.Paste")
			(net "NetQ1_1")
			(solder_mask_margin 0)
			(solder_paste_margin 0)
		)
		(pad "2" smd rect
			(at 0.36554 0)
			(size 0.58106 0.47247)
			(layers "F.Cu" "F.Mask" "F.Paste")
			(net "VCC_ANT")
			(solder_mask_margin 0)
			(solder_paste_margin 0)
		)
	)
	(footprint "Vault:FP-RMCF0402-MFG"
		(layer "F.Cu")
		(at 170.8205 103.9597 90)
		(property "Reference" "R2"
			(at 2.35981 0.07907 90)
			(unlocked yes)
			(layer "F.SilkS")
			(effects
				(font
					(size 0.8 0.8)
					(thickness 0.15001)
				)
			)
		)
		(property "Value" "1k"
			(at 0.57117 2.378202 90)
			(unlocked yes)
			(layer "F.SilkS")
			(hide yes)
			(effects
				(font
					(size 1.524 1.524)
					(thickness 0.254)
				)
			)
		)
		(sheetname "ZED-F9T")
		(sheetfile "ZED-F9T.kicad_sch")
		(duplicate_pad_numbers_are_jumpers no)
		(fp_line
			(start -0.55 -0.7)
			(end 0.55 -0.7)
			(stroke
				(width 0.2)
				(type solid)
			)
			(layer "F.SilkS")
		)
		(fp_line
			(start -0.55 0.7)
			(end 0.55 0.7)
			(stroke
				(width 0.2)
				(type solid)
			)
			(layer "F.SilkS")
		)
		(fp_line
			(start 0.85 -0.4)
			(end 0.85 0.4)
			(stroke
				(width 0.2)
				(type solid)
			)
			(layer "F.CrtYd")
		)
		(fp_line
			(start -0.85 -0.4)
			(end 0.85 -0.4)
			(stroke
				(width 0.2)
				(type solid)
			)
			(layer "F.CrtYd")
		)
		(fp_line
			(start -0.85 -0.4)
			(end -0.85 0.4)
			(stroke
				(width 0.2)
				(type solid)
			)
			(layer "F.CrtYd")
		)
		(fp_line
			(start -0.85 0.4)
			(end 0.85 0.4)
			(stroke
				(width 0.2)
				(type solid)
			)
			(layer "F.CrtYd")
		)
		(fp_line
			(start 0 -0.5)
			(end 0 0.5)
			(stroke
				(width 0.1)
				(type solid)
			)
			(layer "F.Fab")
		)
		(fp_line
			(start 0.85 -0.4)
			(end 0.85 0.4)
			(stroke
				(width 0.2)
				(type solid)
			)
			(layer "F.Fab")
		)
		(fp_line
			(start -0.85 -0.4)
			(end 0.85 -0.4)
			(stroke
				(width 0.2)
				(type solid)
			)
			(layer "F.Fab")
		)
		(fp_line
			(start -0.85 -0.4)
			(end -0.85 0.4)
			(stroke
				(width 0.2)
				(type solid)
			)
			(layer "F.Fab")
		)
		(fp_line
			(start -0.5 0)
			(end 0.5 0)
			(stroke
				(width 0.1)
				(type solid)
			)
			(layer "F.Fab")
		)
		(fp_line
			(start -0.85 0.4)
			(end 0.85 0.4)
			(stroke
				(width 0.2)
				(type solid)
			)
			(layer "F.Fab")
		)
		(fp_text user "${REFERENCE}"
			(at -0.00001 0.10711 90)
			(unlocked yes)
			(layer "F.Fab")
			(effects
				(font
					(face "Arial")
					(size 0.63 0.63)
					(thickness 0.1)
				)
				(justify left bottom)
			)
		)
		(pad "1" smd rect
			(at -0.5 0 90)
			(size 0.5 0.6)
			(layers "F.Cu" "F.Mask" "F.Paste")
			(net "RXD")
			(solder_mask_margin 0)
			(solder_paste_margin 0)
		)
		(pad "2" smd rect
			(at 0.5 0 90)
			(size 0.5 0.6)
			(layers "F.Cu" "F.Mask" "F.Paste")
			(net "VCC")
			(solder_mask_margin 0)
			(solder_paste_margin 0)
		)
	)
)
